# S9S_MB_2U (Grand Teton) — schematic netlist excerpt (pin names and nets, part order shuffled) for the footprints in the layout excerpt that follows; sources: Cadence DE-HDL packaged netlist, KiCad conversion of 03242023_DA0F0TMBIJ0_F0T_Motherboard_J_brd_V01_OCP.brd

PC2168  Q_CAP  39PF 50V 5% EMPTY  pkg C0402  page 163 : A = P3V3_OCP_MODE_2 ; B = GND
R1868  Q_RES  10 1% CHIP  pkg 0402LF  page 202 : A = ESPI_LAD0_DATA_IO3 ; B = ESPI_LPC_LAD0_IO3

(kicad_pcb
	(version 20260206)
	(generator "pcbnew")
	(generator_version "10.0")
	(general
		(thickness 1.6)
		(legacy_teardrops no)
	)
	(paper "A4")
	(title_block
		(title "03242023_DA0F0TMBIJ0_F0T_Motherboard_J_brd_V01_OCP.brd")
		(comment 1 "Grand Teton / footprints 1564-1565 of 6105")
	)
	(layers
		(0 "F.Cu" signal "TOP")
		(4 "In1.Cu" signal "GND")
		(6 "In2.Cu" signal "IN1")
		(8 "In3.Cu" signal "GND1")
		(10 "In4.Cu" signal "IN2")
		(12 "In5.Cu" signal "GND2")
		(14 "In6.Cu" signal "IN3")
		(16 "In7.Cu" signal "GND3")
		(18 "In8.Cu" signal "VCC")
		(20 "In9.Cu" signal "VCC1")
		(22 "In10.Cu" signal "GND4")
		(24 "In11.Cu" signal "IN4")
		(26 "In12.Cu" signal "GND5")
		(28 "In13.Cu" signal "IN5")
		(30 "In14.Cu" signal "GND6")
		(32 "In15.Cu" signal "IN6")
		(34 "In16.Cu" signal "GND7")
		(2 "B.Cu" signal "BOTTOM")
		(9 "F.Adhes" user "F.Adhesive")
		(11 "B.Adhes" user "B.Adhesive")
		(13 "F.Paste" user "Package Geometry/Pastemask Top")
		(15 "B.Paste" user "Package Geometry/Pastemask Bottom")
		(5 "F.SilkS" user "Ref Des/Silkscreen Top")
		(7 "B.SilkS" user "Ref Des/Silkscreen Bottom")
		(1 "F.Mask" user "Board Geometry/Soldermask Top")
		(3 "B.Mask" user "Board Geometry/Soldermask Bottom")
		(17 "Dwgs.User" user "User.Drawings")
		(19 "Cmts.User" user "User.Comments")
		(21 "Eco1.User" user "User.Eco1")
		(23 "Eco2.User" user "User.Eco2")
		(25 "Edge.Cuts" user "Board Geometry/Outline")
		(27 "Margin" user)
		(31 "F.CrtYd" user "Package Geometry/Place Bound Top")
		(29 "B.CrtYd" user "Package Geometry/Place Bound Bottom")
		(35 "F.Fab" user "Ref Des/Assembly Top")
		(33 "B.Fab" user "Ref Des/Assembly Bottom")
	)
	(footprint ""
		(layer "F.Cu")
		(at 333.986124 -25.956006 -90)
		(property "Reference" "R1868"
			(at 0 0 270)
			(layer "F.SilkS")
			(hide yes)
			(effects
				(font
					(size 1.27 1.27)
				)
			)
		)
		(property "Value" ""
			(at 0 0 270)
			(layer "F.Fab")
			(effects
				(font
					(size 1.27 1.27)
				)
			)
		)
		(duplicate_pad_numbers_are_jumpers no)
		(fp_line
			(start -0.7874 0.4064)
			(end -0.7874 -0.4064)
			(stroke
				(width 0.1524)
				(type default)
			)
			(layer "F.SilkS")
		)
		(fp_line
			(start 0.7874 0.4064)
			(end -0.7874 0.4064)
			(stroke
				(width 0.1524)
				(type default)
			)
			(layer "F.SilkS")
		)
		(fp_line
			(start -0.7874 -0.4064)
			(end 0.7874 -0.4064)
			(stroke
				(width 0.1524)
				(type default)
			)
			(layer "F.SilkS")
		)
		(fp_line
			(start 0.7874 -0.4064)
			(end 0.7874 0.4064)
			(stroke
				(width 0.1524)
				(type default)
			)
			(layer "F.SilkS")
		)
		(fp_line
			(start -0.67945 0.3048)
			(end -0.67945 -0.305054)
			(stroke
				(width 0.1)
				(type default)
			)
			(layer "F.Fab")
		)
		(fp_line
			(start -0.12065 0.3048)
			(end -0.67945 0.3048)
			(stroke
				(width 0.1)
				(type default)
			)
			(layer "F.Fab")
		)
		(fp_line
			(start 0.120396 0.3048)
			(end 0.120396 0.2794)
			(stroke
				(width 0.1)
				(type default)
			)
			(layer "F.Fab")
		)
		(fp_line
			(start 0.67945 0.3048)
			(end 0.120396 0.3048)
			(stroke
				(width 0.1)
				(type default)
			)
			(layer "F.Fab")
		)
		(fp_line
			(start -0.12065 0.2794)
			(end -0.12065 0.3048)
			(stroke
				(width 0.1)
				(type default)
			)
			(layer "F.Fab")
		)
		(fp_line
			(start 0.120396 0.2794)
			(end -0.12065 0.2794)
			(stroke
				(width 0.1)
				(type default)
			)
			(layer "F.Fab")
		)
		(fp_line
			(start -0.12065 -0.2794)
			(end 0.12065 -0.2794)
			(stroke
				(width 0.1)
				(type default)
			)
			(layer "F.Fab")
		)
		(fp_line
			(start 0.12065 -0.2794)
			(end 0.12065 -0.3048)
			(stroke
				(width 0.1)
				(type default)
			)
			(layer "F.Fab")
		)
		(fp_line
			(start 0.12065 -0.3048)
			(end 0.67945 -0.3048)
			(stroke
				(width 0.1)
				(type default)
			)
			(layer "F.Fab")
		)
		(fp_line
			(start 0.67945 -0.3048)
			(end 0.67945 0.3048)
			(stroke
				(width 0.1)
				(type default)
			)
			(layer "F.Fab")
		)
		(fp_line
			(start -0.67945 -0.305054)
			(end -0.12065 -0.305054)
			(stroke
				(width 0.1)
				(type default)
			)
			(layer "F.Fab")
		)
		(fp_line
			(start -0.12065 -0.305054)
			(end -0.12065 -0.2794)
			(stroke
				(width 0.1)
				(type default)
			)
			(layer "F.Fab")
		)
		(pad "1" smd circle
			(at -0.40005 0 270)
			(size 0 0)
			(layers "F.Cu" "F.Mask" "F.Paste")
			(net "ESPI_LAD0_DATA_IO3")
		)
		(pad "2" smd circle
			(at 0.40005 0 270)
			(size 0 0)
			(layers "F.Cu" "F.Mask" "F.Paste")
			(net "ESPI_LPC_LAD0_IO3")
		)
	)
	(footprint ""
		(layer "F.Cu")
		(at 69.16928 -53.548788 180)
		(property "Reference" "PC2168"
			(at 0 0 180)
			(layer "F.SilkS")
			(hide yes)
			(effects
				(font
					(size 1.27 1.27)
				)
			)
		)
		(property "Value" ""
			(at 0 0 180)
			(layer "F.Fab")
			(effects
				(font
					(size 1.27 1.27)
				)
			)
		)
		(duplicate_pad_numbers_are_jumpers no)
		(fp_line
			(start 0.7874 0.4064)
			(end -0.7874 0.4064)
			(stroke
				(width 0.1524)
				(type default)
			)
			(layer "F.SilkS")
		)
		(fp_line
			(start 0.7874 -0.4064)
			(end 0.7874 0.4064)
			(stroke
				(width 0.1524)
				(type default)
			)
			(layer "F.SilkS")
		)
		(fp_line
			(start -0.7874 0.4064)
			(end -0.7874 -0.4064)
			(stroke
				(width 0.1524)
				(type default)
			)
			(layer "F.SilkS")
		)
		(fp_line
			(start -0.7874 -0.4064)
			(end 0.7874 -0.4064)
			(stroke
				(width 0.1524)
				(type default)
			)
			(layer "F.SilkS")
		)
		(fp_line
			(start 0.67945 0.3048)
			(end 0.120396 0.3048)
			(stroke
				(width 0.1)
				(type default)
			)
			(layer "F.Fab")
		)
		(fp_line
			(start 0.67945 -0.3048)
			(end 0.67945 0.3048)
			(stroke
				(width 0.1)
				(type default)
			)
			(layer "F.Fab")
		)
		(fp_line
			(start 0.12065 -0.2794)
			(end 0.12065 -0.3048)
			(stroke
				(width 0.1)
				(type default)
			)
			(layer "F.Fab")
		)
		(fp_line
			(start 0.12065 -0.3048)
			(end 0.67945 -0.3048)
			(stroke
				(width 0.1)
				(type default)
			)
			(layer "F.Fab")
		)
		(fp_line
			(start 0.120396 0.3048)
			(end 0.120396 0.2794)
			(stroke
				(width 0.1)
				(type default)
			)
			(layer "F.Fab")
		)
		(fp_line
			(start 0.120396 0.2794)
			(end -0.12065 0.2794)
			(stroke
				(width 0.1)
				(type default)
			)
			(layer "F.Fab")
		)
		(fp_line
			(start -0.12065 0.3048)
			(end -0.67945 0.3048)
			(stroke
				(width 0.1)
				(type default)
			)
			(layer "F.Fab")
		)
		(fp_line
			(start -0.12065 0.2794)
			(end -0.12065 0.3048)
			(stroke
				(width 0.1)
				(type default)
			)
			(layer "F.Fab")
		)
		(fp_line
			(start -0.12065 -0.2794)
			(end 0.12065 -0.2794)
			(stroke
				(width 0.1)
				(type default)
			)
			(layer "F.Fab")
		)
		(fp_line
			(start -0.12065 -0.305054)
			(end -0.12065 -0.2794)
			(stroke
				(width 0.1)
				(type default)
			)
			(layer "F.Fab")
		)
		(fp_line
			(start -0.67945 0.3048)
			(end -0.67945 -0.305054)
			(stroke
				(width 0.1)
				(type default)
			)
			(layer "F.Fab")
		)
		(fp_line
			(start -0.67945 -0.305054)
			(end -0.12065 -0.305054)
			(stroke
				(width 0.1)
				(type default)
			)
			(layer "F.Fab")
		)
		(pad "1" smd circle
			(at -0.40005 0 180)
			(size 0 0)
			(layers "F.Cu" "F.Mask" "F.Paste")
			(net "P3V3_OCP_MODE_2")
		)
		(pad "2" smd circle
			(at 0.40005 0 180)
			(size 0 0)
			(layers "F.Cu" "F.Mask" "F.Paste")
			(net "GND")
		)
	)
)
